FILE_TYPE = CONNECTIVITY;
{Allegro Design Entry HDL 16.6-p007 (v16-6-112F) 10/10/2012}
"PAGE_NUMBER" = 237;
0"NC";
1"GND\g";
2"GND\g";
3"GND\g";
4"P1V8_PCH_STBY\g";
5"GND\g";
6"P3V3_STBY\g";
7"GND\g"VOLTAGE"0 V";
8"P3V3_STBY\g";
9"GND\g";
10"GND\g"VOLTAGE"0V";
11"PWRGD_P1V8_PCH_STBY";
12"VR_P1V8_PCH_STBY_FB";
13"PWRGD_P1V8_PCH_STBY_R";
14"PWRGD_P3V3_STBY";
%"CAP"
"1","(3375,2150)","0","mstr_discrete","I12";
;
CDS_SEC"1"
$SEC"1"
ROOM"P1V8_PCH_STBY_VR"
BOM_COST"P1V8_PCH_STBY_VR"
CDS_LOCATION"C2L45"
CDS_LIB"mstr_discrete"
TOLERANCE"20%"
VOLTAGE"6.3V"
MATERIAL"X6S"
VALUE"22UF"
LOCATION"C2L45"
PART_NUMBER"C95333-008"
PACK_TYPE"0805";
"A"
$PN"1"4;
"B"
$PN"2"1;
%"CAP"
"1","(3100,2200)","0","mstr_discrete","I13";
;
CDS_SEC"1"
SEC"1"
ROOM"P1V8_PCH_STBY_VR"
BOM_COST"P1V8_PCH_STBY_VR"
SEC_TYPE"0805"
CDS_LOCATION"C8A14"
CDS_LIB"mstr_discrete"
PART_NUMBER"C95333-008"
LOCATION"C8A14"
MATERIAL"X6S"
VOLTAGE"6.3V"
TOLERANCE"20%"
VALUE"22UF"
PACK_TYPE"0805";
"A"
$PN"1"4;
"B"
$PN"2"1;
%"GND"
"1","(3500,1400)","0","mstr_symbols","I14";
;
HDL_POWER"GND"
BOM_COST"P1V8_PCH_STBY_VR"
BODY_TYPE"PLUMBING"
SIZE"1B"
CDS_LIB"mstr_symbols"
VOLTAGE"0.0V"
ROOM"P1V8_PCH_STBY_VR";
"A\NAC"1;
%"RES"
"2","(2800,2125)","0","mstr_discrete","I15";
;
CDS_SEC"1"
SEC_TYPE"0603"
BOM_COST"P1V8_PCH_STBY_VR"
SEC"1"
CDS_LOCATION"R8A12"
ROOM"P1V8_PCH_STBY_VR"
CDS_LIB"mstr_discrete"
LOCATION"R8A12"
VALUE"475.0"
TOLERANCE"1%"
MATERIAL"CHIP"
WATTAGE"1/10W"
PART_NUMBER"G22026-030"
PACK_TYPE"0603";
"A"
$PN"1"4;
"B"
$PN"2"1;
%"CAP"
"1","(-1975,3150)","0","mstr_discrete","I29";
;
CDS_SEC"1"
SEC_TYPE"0603"
SEC"1"
BOM_COST"P1V8_PCH_STBY_VR"
ROOM"P1V8_PCH_STBY_VR"
CDS_LOCATION"C8A6"
CDS_LIB"mstr_discrete"
VOLTAGE"6.3V"
TOLERANCE"20%"
VALUE"10UF"
LOCATION"C8A6"
MATERIAL"X6S"
PACK_TYPE"0603"
PART_NUMBER"E15431-002";
"A"
$PN"1"8;
"B"
$PN"2"2;
%"RES"
"2","(1350,3875)","0","mstr_discrete","I3";
;
CDS_SEC"1"
$SEC"1"
BOM_COST"P1V8_PCH_STBY_VR"
ROOM"P1V8_PCH_STBY_VR"
CDS_LOCATION"R8A10"
CDS_LIB"mstr_discrete"
LOCATION"R8A10"
PART_NUMBER"G21796-140"
VALUE"5.11K"
WATTAGE"1/16W"
TOLERANCE"1%"
MATERIAL"CHIP"
PACK_TYPE"0402";
"A"
$PN"1"6;
"B"
$PN"2"13;
%"GND"
"1","(-1975,2800)","0","mstr_symbols","I30";
;
HDL_POWER"GND"
CDS_LIB"mstr_symbols"
BODY_TYPE"PLUMBING"
SIZE"1B"
VOLTAGE"0.0V"
BOM_COST"P1V8_PCH_STBY_VR"
ROOM"P1V8_PCH_STBY_VR";
"A\NAC"2;
%"CAP"
"1","(-1550,3175)","0","mstr_discrete","I31";
;
CDS_SEC"1"
BOM_COST"P1V8_PCH_STBY_VR"
SEC_TYPE"0603LF"
SEC"1"
CDS_LOCATION"C8A4"
ROOM"P1V8_PCH_STBY_VR"
CDS_LIB"mstr_discrete"
PART_NUMBER"602433-020"
LOCATION"C8A4"
VALUE"0.1UF"
TOLERANCE"10%"
VOLTAGE"25V"
MATERIAL"X7R"
PACK_TYPE"0603LF";
"A"
$PN"1"8;
"B"
$PN"2"3;
%"GND"
"1","(-1550,2775)","0","mstr_symbols","I32";
;
SIZE"1B"
HDL_POWER"GND"
BODY_TYPE"PLUMBING"
CDS_LIB"mstr_symbols"
VOLTAGE"0.0V"
BOM_COST"P1V8_PCH_STBY_VR"
ROOM"P1V8_PCH_STBY_VR";
"A\NAC"3;
%"P1V8_PCH_STBY"
"1","(3925,2850)","0","mstr_symbols","I4";
;
CDS_LIB"mstr_symbols"
BOM_COST"P1V8_PCH_STBY_VR"
ROOM"P1V8_PCH_STBY_VR"
HDL_POWER"P1V8_PCH_STBY"
VOLTAGE"1.8V"
BODY_TYPE"PLUMBING";
"G\NAC"4;
%"CAP"
"1","(1350,3475)","0","mstr_discrete","I5";
;
$SEC"1"
ROOM"P1V8_PCH_STBY_VR"
BOM_COST"P1V8_PCH_STBY_VR"
CDS_SEC"1"
CDS_LOCATION"C8A11"
CDS_LIB"mstr_discrete"
LOCATION"C8A11"
PART_NUMBER"A36096-046"
VALUE"1000PF"
PACK_TYPE"0402LF"
TOLERANCE"10%"
VOLTAGE"50V"
MATERIAL"X7R";
"A"
$PN"1"13;
"B"
$PN"2"5;
%"CAP"
"1","(-1500,2200)","2","mstr_discrete","I55";
;
CDS_LIB"mstr_discrete"
BOM_COST"P1V8_PCH_STBY_VR"
CDS_SEC"1"
$SEC"1"
ROOM"P1V8_PCH_STBY_VR"
CDS_LOCATION"C8A10"
PACK_TYPE"0402LF"
VOLTAGE"50V"
TOLERANCE"10%"
MATERIAL"EMPTY"
LOCATION"C8A10"
VALUE"1000PF"
PART_NUMBER"A36096-046";
"A"
$PN"1"14;
"B"
$PN"2"10;
%"GND"
"1","(1350,3150)","0","mstr_symbols","I6";
;
HDL_POWER"GND"
SIZE"1B"
VOLTAGE"0.0V"
CDS_LIB"mstr_symbols"
BODY_TYPE"PLUMBING"
BOM_COST"P1V8_PCH_STBY_VR"
ROOM"P1V8_PCH_STBY_VR";
"A\NAC"5;
%"P3V3_STBY"
"1","(1350,4125)","0","mstr_symbols","I65";
;
SIZE"1B"
CDS_LIB"mstr_symbols"
VOLTAGE"3.3V"
BODY_TYPE"PLUMBING"
HDL_POWER"P3V3_STBY";
"G\NAC"6;
%"GND"
"1","(525,2300)","0","mstr_symbols","I71";
;
CDS_LIB"mstr_symbols"
SIZE"1B"
HDL_POWER"GND"
VOLTAGE"0.0V"
BOM_COST"P1V8_PCH_STBY_VR"
BODY_TYPE"PLUMBING"
ROOM"P1V8_PCH_STBY_VR";
"A\NAC"7;
%"CAP"
"1","(3650,2200)","0","mstr_discrete","I77";
;
CDS_SEC"1"
SEC_TYPE"0805"
SEC"1"
ROOM"P1V8_PCH_STBY_VR"
CDS_LOCATION"C8A12"
CDS_LIB"mstr_discrete"
PART_NUMBER"C95333-006"
LOCATION"C8A12"
TOLERANCE"20%"
VOLTAGE"4V"
MATERIAL"X6S"
VALUE"47UF"
PACK_TYPE"0805";
"A"
$PN"1"4;
"B"
$PN"2"1;
%"CAP"
"1","(3900,1850)","0","mstr_discrete","I79";
;
CDS_SEC"1"
SEC_TYPE"0805"
SEC"1"
ROOM"P1V8_PCH_STBY_VR"
CDS_LOCATION"C2L32"
CDS_LIB"mstr_discrete"
PART_NUMBER"C95333-006"
VOLTAGE"4V"
TOLERANCE"20%"
VALUE"47UF"
LOCATION"C2L32"
PACK_TYPE"0805"
MATERIAL"X6S";
"A"
$PN"1"4;
"B"
$PN"2"1;
%"RES"
"2","(2325,1700)","0","mstr_discrete","I80";
;
CDS_SEC"1"
ROOM"P1V8_PCH_STBY_VR"
SEC_TYPE"0402"
SEC"1"
CDS_LOCATION"R2L19"
CDS_LIB"mstr_discrete"
PART_NUMBER"G21796-048"
LOCATION"R2L19"
VALUE"49.9K"
WATTAGE"1/16W"
MATERIAL"CHIP"
TOLERANCE"1%"
PACK_TYPE"0402";
"A"
$PN"1"12;
"B"
$PN"2"9;
%"RES"
"2","(2325,2275)","0","mstr_discrete","I81";
;
CDS_SEC"1"
CDS_LOCATION"R2L20"
SEC"1"
ROOM"P1V8_PCH_STBY_VR"
SEC_TYPE"0402"
CDS_LIB"mstr_discrete"
PART_NUMBER"G21796-327"
VALUE"63.4K"
LOCATION"R2L20"
TOLERANCE"1.0%"
WATTAGE"1/16W"
PACK_TYPE"0402"
MATERIAL"CHIP";
"A"
$PN"1"4;
"B"
$PN"2"12;
%"P3V3_STBY"
"1","(-1750,3650)","0","mstr_symbols","I85";
;
VOLTAGE"3.3V"
CDS_LIB"mstr_symbols"
SIZE"1B"
BODY_TYPE"PLUMBING"
HDL_POWER"P3V3_STBY";
"G\NAC"8;
%"RT9059"
"1","(-50,2725)","0","mstr_vreg","I86";
;
CDS_SEC"1"
PACK_TYPE"DFN"
SEC_TYPE"DFN"
SEC"1"
CDS_LOCATION"EU8A2"
ROOM"P1V8_PCH_STBY_VR"
CDS_LIB"mstr_vreg"
LOCATION"EU8A2"
MATERIAL"IC"
PART_NUMBER"H65765-001";
"VIN<0>"
$PN"7"8;
"VIN<1>"
$PN"8"8;
"VIN<2>"
$PN"9"8;
"EN"
$PN"6"14;
"VOUT<0>"
$PN"1"4;
"VOUT<1>"
$PN"2"4;
"VOUT<2>"
$PN"3"4;
"GND"
$PN"11"7;
"ADJ_NC"
$PN"4"12;
"VDD"
$PN"10"8;
"PGOOD"
$PN"5"13;
%"RES"
"1","(2175,3650)","0","mstr_discrete","I90";
;
CDS_SEC"1"
ROOM"P1V8_PCH_STBY_VR"
SEC"1"
SEC_TYPE"0402"
CDS_LIB"mstr_discrete"
CDS_LOCATION"R8A11"
PART_NUMBER"G21796-250"
LOCATION"R8A11"
TOLERANCE"1.0%"
PACK_TYPE"0402"
MATERIAL"CHIP"
VALUE"22.1"
WATTAGE"1/16W";
"B"
$PN"2"11;
"A"
$PN"1"13;
%"GND"
"1","(2325,1425)","0","mstr_symbols","I91";
;
HDL_POWER"GND"
VOLTAGE"0.0V"
SIZE"1B"
CDS_LIB"mstr_symbols"
BODY_TYPE"PLUMBING"
ROOM"P1V8_PCH_STBY_VR"
BOM_COST"P1V8_PCH_STBY_VR";
"A\NAC"9;
%"GND"
"1","(-1500,1950)","0","mstr_symbols","I92";
;
HDL_POWER"GND"
BOM_COST"P1V8_PCH_STBY_VR"
VOLTAGE"0.0V"
SIZE"1B"
CDS_LIB"mstr_symbols"
BODY_TYPE"PLUMBING"
ROOM"P1V8_PCH_STBY_VR";
"A\NAC"10;
END.
